FILE_TYPE=LIBRARY_PARTS;
primitive 'M24M02DRMN6TP';
  pin
    'VCC':
      PIN_NUMBER='(8)';
      PINUSE='POWER';
      NO_LOAD_CHECK='Both';
      NO_IO_CHECK='Both';
      NO_ASSERT_CHECK='TRUE';
      NO_DIR_CHECK='TRUE';
      ALLOW_CONNECT='TRUE';
    '-WC':
      PIN_NUMBER='(7)';
      INPUT_LOAD='(-0.01,0.01)';
    'SCL':
      PIN_NUMBER='(6)';
      INPUT_LOAD='(-0.01,0.01)';
    'SDA':
      PIN_NUMBER='(5)';
      BIDIRECTIONAL='TRUE';
      INPUT_LOAD='(-0.01,0.01)';
      OUTPUT_LOAD='(1.0,-1.0)';
    'VSS':
      PIN_NUMBER='(4)';
      PINUSE='POWER';
      NO_LOAD_CHECK='Both';
      NO_IO_CHECK='Both';
      NO_ASSERT_CHECK='TRUE';
      NO_DIR_CHECK='TRUE';
      ALLOW_CONNECT='TRUE';
    'E2':
      PIN_NUMBER='(3)';
      INPUT_LOAD='(-0.01,0.01)';
    'DU2':
      PIN_NUMBER='(2)';
      INPUT_LOAD='(-0.01,0.01)';
    'DU1':
      PIN_NUMBER='(1)';
      INPUT_LOAD='(-0.01,0.01)';
  end_pin;
  body
    PART_NAME='M24M02DRMN6TP';
    BODY_NAME='M24M02DRMN6TP';
    PHYS_DES_PREFIX='U';
    CLASS='IC';
  end_body;
end_primitive;

END.
